# S9S_MB_2U (Grand Teton) — schematic netlist excerpt (pin names and nets, part order shuffled) for the footprints in the layout excerpt that follows; sources: Cadence DE-HDL packaged netlist, KiCad conversion of 03242023_DA0F0TMBIJ0_F0T_Motherboard_J_brd_V01_OCP.brd

PR4240  Q_RES  499 1% CHIP  pkg 0402LF  page 285 : A = PVCCIN_CPU1 ; B = GND
R909  Q_RES  33.2 1% CHIP  pkg 0402LF  page 235 : A = SMB_PEHPCPU0_GTL_SDA ; B = SMB_PEHPCPU0_GTL_R_SDA

(kicad_pcb
	(version 20260206)
	(generator "pcbnew")
	(generator_version "10.0")
	(general
		(thickness 1.6)
		(legacy_teardrops no)
	)
	(paper "A4")
	(title_block
		(title "03242023_DA0F0TMBIJ0_F0T_Motherboard_J_brd_V01_OCP.brd")
		(comment 1 "Grand Teton / footprints 4591-4592 of 6105")
	)
	(layers
		(0 "F.Cu" signal "TOP")
		(4 "In1.Cu" signal "GND")
		(6 "In2.Cu" signal "IN1")
		(8 "In3.Cu" signal "GND1")
		(10 "In4.Cu" signal "IN2")
		(12 "In5.Cu" signal "GND2")
		(14 "In6.Cu" signal "IN3")
		(16 "In7.Cu" signal "GND3")
		(18 "In8.Cu" signal "VCC")
		(20 "In9.Cu" signal "VCC1")
		(22 "In10.Cu" signal "GND4")
		(24 "In11.Cu" signal "IN4")
		(26 "In12.Cu" signal "GND5")
		(28 "In13.Cu" signal "IN5")
		(30 "In14.Cu" signal "GND6")
		(32 "In15.Cu" signal "IN6")
		(34 "In16.Cu" signal "GND7")
		(2 "B.Cu" signal "BOTTOM")
		(9 "F.Adhes" user "F.Adhesive")
		(11 "B.Adhes" user "B.Adhesive")
		(13 "F.Paste" user "Package Geometry/Pastemask Top")
		(15 "B.Paste" user "Package Geometry/Pastemask Bottom")
		(5 "F.SilkS" user "Ref Des/Silkscreen Top")
		(7 "B.SilkS" user "Ref Des/Silkscreen Bottom")
		(1 "F.Mask" user "Board Geometry/Soldermask Top")
		(3 "B.Mask" user "Board Geometry/Soldermask Bottom")
		(17 "Dwgs.User" user "User.Drawings")
		(19 "Cmts.User" user "User.Comments")
		(21 "Eco1.User" user "User.Eco1")
		(23 "Eco2.User" user "User.Eco2")
		(25 "Edge.Cuts" user "Board Geometry/Outline")
		(27 "Margin" user)
		(31 "F.CrtYd" user "Package Geometry/Place Bound Top")
		(29 "B.CrtYd" user "Package Geometry/Place Bound Bottom")
		(35 "F.Fab" user "Ref Des/Assembly Top")
		(33 "B.Fab" user "Ref Des/Assembly Bottom")
	)
	(footprint ""
		(layer "B.Cu")
		(at 99.26828 -325.084948 -90)
		(property "Reference" "PR4240"
			(at 0 0 90)
			(layer "B.SilkS")
			(hide yes)
			(effects
				(font
					(size 1.27 1.27)
				)
				(justify mirror)
			)
		)
		(property "Value" ""
			(at 0 0 90)
			(layer "B.Fab")
			(effects
				(font
					(size 1.27 1.27)
				)
				(justify mirror)
			)
		)
		(duplicate_pad_numbers_are_jumpers no)
		(fp_line
			(start -0.7874 0.4064)
			(end 0.7874 0.4064)
			(stroke
				(width 0.1524)
				(type default)
			)
			(layer "B.SilkS")
		)
		(fp_line
			(start 0.7874 0.4064)
			(end 0.7874 -0.4064)
			(stroke
				(width 0.1524)
				(type default)
			)
			(layer "B.SilkS")
		)
		(fp_line
			(start -0.7874 -0.4064)
			(end -0.7874 0.4064)
			(stroke
				(width 0.1524)
				(type default)
			)
			(layer "B.SilkS")
		)
		(fp_line
			(start 0.7874 -0.4064)
			(end -0.7874 -0.4064)
			(stroke
				(width 0.1524)
				(type default)
			)
			(layer "B.SilkS")
		)
		(fp_line
			(start -0.67945 0.3048)
			(end -0.120396 0.3048)
			(stroke
				(width 0.1)
				(type default)
			)
			(layer "B.Fab")
		)
		(fp_line
			(start -0.120396 0.3048)
			(end -0.120396 0.2794)
			(stroke
				(width 0.1)
				(type default)
			)
			(layer "B.Fab")
		)
		(fp_line
			(start 0.12065 0.3048)
			(end 0.67945 0.3048)
			(stroke
				(width 0.1)
				(type default)
			)
			(layer "B.Fab")
		)
		(fp_line
			(start 0.67945 0.3048)
			(end 0.67945 -0.305054)
			(stroke
				(width 0.1)
				(type default)
			)
			(layer "B.Fab")
		)
		(fp_line
			(start -0.120396 0.2794)
			(end 0.12065 0.2794)
			(stroke
				(width 0.1)
				(type default)
			)
			(layer "B.Fab")
		)
		(fp_line
			(start 0.12065 0.2794)
			(end 0.12065 0.3048)
			(stroke
				(width 0.1)
				(type default)
			)
			(layer "B.Fab")
		)
		(fp_line
			(start -0.12065 -0.2794)
			(end -0.12065 -0.3048)
			(stroke
				(width 0.1)
				(type default)
			)
			(layer "B.Fab")
		)
		(fp_line
			(start 0.12065 -0.2794)
			(end -0.12065 -0.2794)
			(stroke
				(width 0.1)
				(type default)
			)
			(layer "B.Fab")
		)
		(fp_line
			(start -0.67945 -0.3048)
			(end -0.67945 0.3048)
			(stroke
				(width 0.1)
				(type default)
			)
			(layer "B.Fab")
		)
		(fp_line
			(start -0.12065 -0.3048)
			(end -0.67945 -0.3048)
			(stroke
				(width 0.1)
				(type default)
			)
			(layer "B.Fab")
		)
		(fp_line
			(start 0.12065 -0.305054)
			(end 0.12065 -0.2794)
			(stroke
				(width 0.1)
				(type default)
			)
			(layer "B.Fab")
		)
		(fp_line
			(start 0.67945 -0.305054)
			(end 0.12065 -0.305054)
			(stroke
				(width 0.1)
				(type default)
			)
			(layer "B.Fab")
		)
		(pad "1" smd circle
			(at 0.40005 0 90)
			(size 0 0)
			(layers "B.Cu" "B.Mask" "B.Paste")
			(net "PVCCIN_CPU1")
		)
		(pad "2" smd circle
			(at -0.40005 0 90)
			(size 0 0)
			(layers "B.Cu" "B.Mask" "B.Paste")
			(net "GND")
		)
	)
	(footprint ""
		(layer "B.Cu")
		(at 374.562624 -190.703454 90)
		(property "Reference" "R909"
			(at 0 0 90)
			(layer "B.SilkS")
			(hide yes)
			(effects
				(font
					(size 1.27 1.27)
				)
				(justify mirror)
			)
		)
		(property "Value" ""
			(at 0 0 90)
			(layer "B.Fab")
			(effects
				(font
					(size 1.27 1.27)
				)
				(justify mirror)
			)
		)
		(duplicate_pad_numbers_are_jumpers no)
		(fp_line
			(start 0.7874 -0.4064)
			(end -0.7874 -0.4064)
			(stroke
				(width 0.1524)
				(type default)
			)
			(layer "B.SilkS")
		)
		(fp_line
			(start -0.7874 -0.4064)
			(end -0.7874 0.4064)
			(stroke
				(width 0.1524)
				(type default)
			)
			(layer "B.SilkS")
		)
		(fp_line
			(start 0.7874 0.4064)
			(end 0.7874 -0.4064)
			(stroke
				(width 0.1524)
				(type default)
			)
			(layer "B.SilkS")
		)
		(fp_line
			(start -0.7874 0.4064)
			(end 0.7874 0.4064)
			(stroke
				(width 0.1524)
				(type default)
			)
			(layer "B.SilkS")
		)
		(fp_line
			(start 0.67945 -0.305054)
			(end 0.12065 -0.305054)
			(stroke
				(width 0.1)
				(type default)
			)
			(layer "B.Fab")
		)
		(fp_line
			(start 0.12065 -0.305054)
			(end 0.12065 -0.2794)
			(stroke
				(width 0.1)
				(type default)
			)
			(layer "B.Fab")
		)
		(fp_line
			(start -0.12065 -0.3048)
			(end -0.67945 -0.3048)
			(stroke
				(width 0.1)
				(type default)
			)
			(layer "B.Fab")
		)
		(fp_line
			(start -0.67945 -0.3048)
			(end -0.67945 0.3048)
			(stroke
				(width 0.1)
				(type default)
			)
			(layer "B.Fab")
		)
		(fp_line
			(start 0.12065 -0.2794)
			(end -0.12065 -0.2794)
			(stroke
				(width 0.1)
				(type default)
			)
			(layer "B.Fab")
		)
		(fp_line
			(start -0.12065 -0.2794)
			(end -0.12065 -0.3048)
			(stroke
				(width 0.1)
				(type default)
			)
			(layer "B.Fab")
		)
		(fp_line
			(start 0.12065 0.2794)
			(end 0.12065 0.3048)
			(stroke
				(width 0.1)
				(type default)
			)
			(layer "B.Fab")
		)
		(fp_line
			(start -0.120396 0.2794)
			(end 0.12065 0.2794)
			(stroke
				(width 0.1)
				(type default)
			)
			(layer "B.Fab")
		)
		(fp_line
			(start 0.67945 0.3048)
			(end 0.67945 -0.305054)
			(stroke
				(width 0.1)
				(type default)
			)
			(layer "B.Fab")
		)
		(fp_line
			(start 0.12065 0.3048)
			(end 0.67945 0.3048)
			(stroke
				(width 0.1)
				(type default)
			)
			(layer "B.Fab")
		)
		(fp_line
			(start -0.120396 0.3048)
			(end -0.120396 0.2794)
			(stroke
				(width 0.1)
				(type default)
			)
			(layer "B.Fab")
		)
		(fp_line
			(start -0.67945 0.3048)
			(end -0.120396 0.3048)
			(stroke
				(width 0.1)
				(type default)
			)
			(layer "B.Fab")
		)
		(pad "1" smd circle
			(at 0.40005 0 270)
			(size 0 0)
			(layers "B.Cu" "B.Mask" "B.Paste")
			(net "SMB_PEHPCPU0_GTL_SDA")
		)
		(pad "2" smd circle
			(at -0.40005 0 270)
			(size 0 0)
			(layers "B.Cu" "B.Mask" "B.Paste")
			(net "SMB_PEHPCPU0_GTL_R_SDA")
		)
	)
)
